G04*
G04 #@! TF.GenerationSoftware,Altium Limited,Altium Designer,23.7.1 (13)*
G04*
G04 Layer_Color=0*
%FSLAX25Y25*%
%MOIN*%
G70*
G04*
G04 #@! TF.SameCoordinates,AF00DCEB-AC48-4C7C-91EA-99F42E284231*
G04*
G04*
G04 #@! TF.FilePolarity,Positive*
G04*
G01*
G75*
M02*
